# BASEBOARD_FAB2 (Tioga Pass) — schematic parts with pin connectivity, parts 4101–4254 of 4751; source: Cadence DE-HDL packaged netlist (pstxprt.dat, pstxnet.dat, pstchip.dat)

R9G9  RES  0.0 5% CHIP  pkg 0402  page 141 : 1 = NIC_SER_P_MDI_3_DP ; 2 = NIC_MDI_SPRV_RJ45_3_R_DP
R9G11  RES  0.0 5% CHIP  pkg 0402  page 141 : 1 = NIC_SER_N_MDI_3_DN ; 2 = NIC_MDI_SPRV_RJ45_3_R_DN
R9G12  RES  20.0 1% CHIP  pkg 0402  page 159 : 1 = SMB_OCP_LAN_STBY_LVC3_SDA ; 2 = SMB_SPRINGVILLE_STBY_LVC3_SDA
R9G13  RES  20.0 1% CHIP  pkg 0402  page 159 : 1 = SMB_OCP_LAN_STBY_LVC3_SCL ; 2 = SMB_SPRINGVILLE_STBY_LVC3_SCL
R9G14  RES  20.0 1% CHIP  pkg 0402  page 167 : 1 = SMB_SENSOR_BMC_STBY_LVC3_SCL ; 2 = SMB_SENSOR_STBY_LVC3_SCL
R9G15  RES  20.0 1% CHIP  pkg 0402  page 167 : 1 = SMB_SENSOR_BMC_STBY_LVC3_SDA ; 2 = SMB_SENSOR_STBY_LVC3_SDA
R9G17  RES  0.0 5% CHIP  pkg 0402  page 141 : 1 = NIC_SET_N_MDI_2_DN ; 2 = NIC_MDI_SPRV_RJ45_2_R_DN
R9G18  RES  0.0 5% CHIP  pkg 0402  page 141 : 1 = NIC_SET_P_MDI_2_DP ; 2 = NIC_MDI_SPRV_RJ45_2_R_DP
R9G19  RES  0.0 5% CHIP  pkg 0402  page 141 : 1 = NIC_MDI_SPRV_RJ45_1_DP ; 2 = NIC_MDI_SPRV_RJ45_1_R_DP
R9G20  RES  0.0 5% CHIP  pkg 0402  page 141 : 1 = NIC_MDI_SPRV_RJ45_1_DN ; 2 = NIC_MDI_SPRV_RJ45_1_R_DN
R9G22  RES  0.0 5% CHIP  pkg 0402  page 141 : 1 = NIC_MDI_SPRV_RJ45_0_DN ; 2 = NIC_MDI_SPRV_RJ45_0_R_DN
R9G24  RES  0.0 5% CHIP  pkg 0402  page 141 : 1 = NIC_MDI_SPRV_RJ45_0_DP ; 2 = NIC_MDI_SPRV_RJ45_0_R_DP
R9G26  RES  100.0K 1% CHIP  pkg 0402  page 169 : 1 = A_P3V_BAT_SCALED ; 2 = GND
R9G27  RES  0.0 5% EMPTY  pkg 0402  page 152 : 1 = H_CPU0_MEMDEF_MEMHOT_G_PCH_N ; 2 = H_CPU0_MEMDEF_MEMHOT_LVT3_K_N
R9G28  RES  0.0 5% CHIP  pkg 0402  page 152 : 1 = H_CPU1_KLM_MEMHOT_LVT3_R_N ; 2 = H_CPU1_MEMKLM_MEMHOT_LVT3_K_N
R9G29  RES  0.0 5% CHIP  pkg 0402  page 152 : 1 = H_CPU0_MEMDEF_MEMHOT_LVT3_N ; 2 = H_CPU0_MEMDEF_MEMHOT_LVT3_BMC_N
R9G30  RES  0.0 5% EMPTY  pkg 0402  page 152 : 1 = H_CPU0_MEMDEF_MEMHOT_LVT3_N ; 2 = H_CPU0_MEMDEF_MEMHOT_PCH_N
R9G31  RES  33.2 1% CHIP  pkg 0402  page 152 : 1 = H_CPU0_MEMDEF_MEMHOT_LVT3_K_N ; 2 = H_CPU0_MEMDEF_MEMHOT_LVT3_N
R9G32  RES  0.0 5% CHIP  pkg 0402  page 152 : 1 = H_CPU1_GHJ_MEMHOT_LVT3_R_N ; 2 = H_CPU1_MEMGHJ_MEMHOT_LVT3_K_N
R9G33  RES  0.0 5% CHIP  pkg 0402  page 152 : 1 = H_CPU0_DEF_MEMHOT_LVT3_R_N ; 2 = H_CPU0_MEMDEF_MEMHOT_LVT3_K_N
R9G34  RES  0.0 5% CHIP  pkg 0402  page 152 : 1 = H_CPU0_MEMABC_MEMHOT_G_N ; 2 = H_CPU0_MEMABC_MEMHOT_G_R_N
R9G35  RES  2.7K 1% CHIP  pkg 0402  page 169 : 1 = P3V3_STBY ; 2 = FM_BATTERY_SENSE_EN_N
R9L1  RES  1.00K 1% CHIP  pkg 0402  page 100 : 1 = M_M_VREF ; 2 = GND
R9L2  RES  1.00K 1% CHIP  pkg 0402  page 100 : 1 = PVDDQ_KLM ; 2 = M_M_VREF
R9L3  RES  2 1.0% CHIP  pkg 0402  page 100 : 1 = M_M_CPU_VREF ; 2 = M_M_VREF
R9L4  RES  0.0 5% CHIP  pkg 0402  page 227 : 1 = VR_PVDDQ_KLM_PH2_VCIN ; 2 = P5V_STBY
R9L6  RES  1.00K 1% CHIP  pkg 0402  page 100 : 1 = M_L_VREF ; 2 = GND
R9L7  RES  1.00K 1% CHIP  pkg 0402  page 100 : 1 = PVDDQ_KLM ; 2 = M_L_VREF
R9L8  RES  2 1.0% CHIP  pkg 0402  page 100 : 1 = M_L_CPU_VREF ; 2 = M_L_VREF
R9L9  RES  0.0 5% CHIP  pkg 0402  page 227 : 1 = VR_PVDDQ_KLM_PH1_VCIN ; 2 = P5V_STBY
R9L11  RES  1.00K 1% CHIP  pkg 0402  page 100 : 1 = M_K_VREF ; 2 = GND
R9M1  RES  1.00K 1% CHIP  pkg 0402  page 100 : 1 = PVDDQ_KLM ; 2 = M_K_VREF
R9M2  RES  2 1.0% CHIP  pkg 0402  page 100 : 1 = M_K_CPU_VREF ; 2 = M_K_VREF
R9M3  RES  0.0 5% CHIP  pkg 0402  page 226 : 1 = P3V3_STBY ; 2 = VR_PVDDQ_KLM_VDD
R9M4  RES  0.002 1% CHIP  pkg 1206  page 197 : 1 = P12V_STBY ; 2 = P12V_NVDIMM_KLM
R9M5  RES  100.0K 1% EMPTY  pkg 0402  page 226 : 1 = P3V3_STBY ; 2 = VR_PVDDQ_KLM_VREN
R9M6  RES  49.9 1% EMPTY  pkg 0402  page 226 : 1 = PVCCIO_CPU1 ; 2 = SVID_CLK1_CPU1_R
R9M7  RES  100.0 1% EMPTY  pkg 0402  page 226 : 1 = PVCCIO_CPU1 ; 2 = SVID_DIO1_CPU1_R
R9M9  RES  0.0 5% CHIP  pkg 0402  page 226 : 1 = FM_PVDDQ_KLM_EN ; 2 = VR_PVDDQ_KLM_VREN
R9M13  RES  20.0 1% CHIP  pkg 0402  page 163 : 1 = SMB_PEHPCPU1_STBY_LVC3_R_SDA ; 2 = SMB_PEHPCPU1_STBY_LVC3_SDA
R9M14  RES  20.0 1% CHIP  pkg 0402  page 163 : 1 = SMB_PEHPCPU1_STBY_LVC3_R_SCL ; 2 = SMB_PEHPCPU1_STBY_LVC3_SCL
R9M16  RES  2.0K 1% CHIP  pkg 0402  page 163 : 1 = P3V3_STBY ; 2 = SMB_PEHPCPU1_STBY_LVC3_R_SDA
R9M17  RES  2.0K 1% CHIP  pkg 0402  page 163 : 1 = P3V3_STBY ; 2 = SMB_PEHPCPU1_STBY_LVC3_R_SCL
R9M18  RES  240 1.0% CHIP  pkg 0402  page 163 : 1 = PVCCIO_CPU1 ; 2 = SMB_CPU1_PE_HP_GTL_R_SDA
R9M19  RES  240 1.0% CHIP  pkg 0402  page 163 : 1 = PVCCIO_CPU1 ; 2 = SMB_CPU1_PE_HP_GTL_R_SCL
R9M20  RES  0.0 5% CHIP  pkg 0402  page 156 : 1 = SMB_LAN_STBY_LVC3_SCL ; 2 = SMB_PIROM_CPU1_SCL
R9M21  RES  0.0 5% CHIP  pkg 0402  page 156 : 1 = SMB_LAN_STBY_LVC3_SDA ; 2 = SMB_PIROM_CPU1_SDA
R9N1  RES  49.9 1% CHIP  pkg 0402  page 55 : 1 = PVCCIO_CPU1 ; 2 = SVID_ALERT1_CPU1_R_N
R9N2  RES  100.0 1% CHIP  pkg 0402  page 55 : 1 = PVCCIO_CPU1 ; 2 = SVID_DIO1_CPU1_R
R9N3  RES  0.0 5% CHIP  pkg 0402  page 210 : 1 = VR_PVSA_CPU1_VCIN ; 2 = P5V_STBY
R9N4  RES  51.1 1.0% CHIP  pkg 0402  page 210 : 1 = PVSA_CPU1 ; 2 = GND
R9N7  RES  3.16K 1% CHIP  pkg 0402  page 206 : 1 = VR_PVCCIN_CPU1_XADDR2 ; 2 = GND
R9N8  RES  4.02K 1% CHIP  pkg 0402  page 206 : 1 = VR_PVCCIN_CPU1_XADDR1 ; 2 = GND
R9N14  RES  1.00K 1% CHIP  pkg 0402  page 206 : 1 = PVCCIO_CPU1 ; 2 = VR_PVCCIN_CPU1_VREN
R9N16  RES  0.0 5% CHIP  pkg 0402  page 206 : 1 = FM_PVCCIN_PVCCSA_CPU1_EN_LVC1 ; 2 = VR_PVCCIN_CPU1_VREN
R9P1  RES  100.0 1% CHIP  pkg 0402  page 206 : 1 = PVCCIO_CPU1 ; 2 = SVID_DIO0_CPU1_R
R9P2  RES  49.9 1% CHIP  pkg 0402  page 206 : 1 = PVCCIO_CPU1 ; 2 = SVID_CLK0_CPU1_R
R9P3  RES  33.2 1% CHIP  pkg 0402  page 206 : 1 = IRQ_PVCCIN_CPU1_VRHOT_LVC3_R_N ; 2 = IRQ_PVCCIN_CPU1_VRHOT_LVC3_N
R9P4  RES  2.7K 1% CHIP  pkg 0402  page 200 : 1 = P3V3_STBY ; 2 = IRQ_UV_DETECT_N
R9P5  RES  10.0K 1% CHIP  pkg 0402  page 200 : 1 = P3V3_STBY ; 2 = FM_DISABLE_FAN_N
R9P6  RES  10.0K 1% CHIP  pkg 0402  page 200 : 1 = P3V3_STBY ; 2 = FM_UV_ADR_TRIGGER_N
R9P7  RES  100.0K 1% CHIP  pkg 0402  page 200 : 1 = P12V_STBY ; 2 = A_P12V_STBY_ADR_TRIGGER
R9P8  RES  0.0 5% CHIP  pkg 0402  page 208 : 1 = VR_PVCCIN_CPU1_PH4_VCIN ; 2 = P5V_STBY
R9P9  RES  3.74K 1% CHIP  pkg 0402  page 200 : 1 = A_P12V_STBY_ADR_TRIGGER ; 2 = AGND_HSC
R9P10  RES  10.0K 1% CHIP  pkg 0402  page 200 : 1 = P3V3_STBY ; 2 = A_P12V_STBY_FPH_GATE
R9P11  RES  10.0K 1% CHIP  pkg 0402  page 200 : 1 = A_P12V_STBY_FP_TRIGGER ; 2 = AGND_HSC
R9P12  RES  4.99K 1% CHIP  pkg 0402  page 200 : 1 = A_HSC_INAP ; 2 = AGND_HSC
R9P13  270KR2F-GP  1%  pkg RCL_GP  page 200 : 1 = P12V_STBY ; 2 = A_P12V_STBY_FP_TRIGGER
R9P15  RES  0.0 5% CHIP  pkg 0402  page 200 : 1 = A_HSC_LOW_DRAIN ; 2 = IRQ_OC_DETECT_N
R9P16  RES  0.0 5% CHIP  pkg 0402  page 199 : 1 = FM_P12V_HSC_ADR2 ; 2 = AGND_HSC
R9P17  RES  150.0K 1% CHIP  pkg 0402  page 199 : 1 = FM_P12V_HSC_ADR1 ; 2 = AGND_HSC
R9P18  RES  15.0K 1% CHIP  pkg 0402  page 199 : 1 = P12V_STBY ; 2 = PWRGD_P12V_R
R9P19  RES  10.0K 1% EMPTY  pkg 0402  page 200 : 1 = A_HSC_TIMER_R ; 2 = AGND_HSC
R9P20  RES  2.7K 1% CHIP  pkg 0402  page 200 : 1 = P3V3_STBY ; 2 = FM_HSC_TIMER_EXP_N
R9P21  RES  0.0 5% CHIP  pkg 0402  page 200 : 1 = A_HSC_TIMER ; 2 = A_HSC_TIMER_R
R9P22  RES  0.0 5% CHIP  pkg 0402  page 208 : 1 = VR_PVCCIN_CPU1_PH3_VCIN ; 2 = P5V_STBY
R9P23  RES  100.0K 1% CHIP  pkg 0402  page 199 : 1 = P12V_STBY ; 2 = A_HSC_PWGIN
R9P24  RES  12.1K 1% CHIP  pkg 0402  page 199 : 1 = A_HSC_PWGIN ; 2 = AGND_HSC
R9P26  RES  10.0 1% CHIP  pkg 0402  page 200 : 1 = P12V_HSC_SENN1 ; 2 = A_HSC_HSN
R9P27  RES  10.0 1% CHIP  pkg 0402  page 200 : 1 = P12V_HSC_SENP1 ; 2 = A_HSC_HSP
R9P28  RES  100.0K 1% CHIP  pkg 0402  page 199 : 1 = P12V_PSU ; 2 = A_HSC_OV
R9P29  RES  100.0K 1% CHIP  pkg 0402  page 199 : 1 = P12V_PSU ; 2 = A_HSC_UV
R9P30  RES  10.0 1% CHIP  pkg 0603  page 199 : 1 = P12V_PSU ; 2 = P12V_HSC_VCC
R9P32  RES  0.0 5% CHIP  pkg 0402  page 209 : 1 = VR_PVCCIN_CPU1_PH5_VCIN ; 2 = P5V_STBY
R9P33  RES  100.0K 1% CHIP  pkg 0402  page 200 : 1 = P12V_STBY ; 2 = A_HSC_INAP

R9R1  RES_PWR  0.001 1% CHIP  pkg 6PAD  page 200
  1  \1\  UNSPEC  = P12V_PSU
  2  \2\  UNSPEC  = P12V_MB0_SW
  3  \3\  UNSPEC  = P12V_HSC_SENP1
  4  \4\  UNSPEC  = P12V_HSC_SENN1
  5  \5\  UNSPEC  = P12V_PSU
  6  \6\  UNSPEC  = P12V_MB0_SW

R9R2  RES  0.0 5% CHIP  pkg 0402  page 207 : 1 = VR_PVCCIN_CPU1_PH1_VCIN ; 2 = P5V_STBY
R9R4  RES  10.0 1% CHIP  pkg 0402  page 200 : 1 = A_HSC_GATE ; 2 = A_HSC_GATE2_R
R9R5  RES  49.9 1% CHIP  pkg 0402  page 167 : 1 = ISENSE_TMP421_2_E ; 2 = ISENSE_TMP421_2_DXP
R9R6  RES  49.9 1% CHIP  pkg 0402  page 167 : 1 = ISENSE_TMP421_2_BC ; 2 = ISENSE_TMP421_2_DXN
R9R7  RES  20.0 1% CHIP  pkg 0402  page 167 : 1 = SMB_SENSOR_TMP421_2_SCL ; 2 = SMB_SENSOR_STBY_LVC3_SCL
R9R8  RES  20.0 1% CHIP  pkg 0402  page 167 : 1 = SMB_SENSOR_TMP421_2_SDA ; 2 = SMB_SENSOR_STBY_LVC3_SDA
R9R9  RES  0.0 5% CHIP  pkg 0402  page 181 : 1 = FAN_TACH3 ; 2 = FAN_TACH3_R
R9R10  RES  0.0 5% CHIP  pkg 0402  page 181 : 1 = FAN_TACH1 ; 2 = FAN_TACH1_R
R9R11  RES  0.0 5% CHIP  pkg 0402  page 207 : 1 = VR_PVCCIN_CPU1_PH2_VCIN ; 2 = P5V_STBY
R9R12  RES  0.0 5% CHIP  pkg 0402  page 181 : 1 = FAN_TACH2 ; 2 = FAN_TACH2_R
R9T1  RES  0.0 5% CHIP  pkg 0402  page 181 : 1 = FAN_PWM_OUT_SYS0_R ; 2 = FAN_PWM_OUT_SYS0_R1
R9T3  RES  6.19K 1% CHIP  pkg 0402  page 181 : 1 = FM_P12V_HOTSWAP0_EN ; 2 = GND
R9T6  RES  15.0K 1% CHIP  pkg 0402  page 181 : 1 = P12V_PSU ; 2 = FM_P12V_HOTSWAP0_EN
R9T8  RES  0.0 5% CHIP  pkg 0402  page 181 : 1 = FM_MATED_IN_N ; 2 = GND
R9T9  RES  4.75K 1% CHIP  pkg 0402  page 181 : 1 = P12V_PSU ; 2 = FM_MATED_IN_N
R9U1  RES  0.0 5% CHIP  pkg 0402  page 224 : 1 = VR_PVDDQ_GHJ_PH1_VCIN ; 2 = P5V_STBY
R9U3  RES  100.0 1% CHIP  pkg 0402  page 223 : 1 = PVCCIO_CPU1 ; 2 = SVID_DIO1_CPU1_R
R9U4  RES  49.9 1% CHIP  pkg 0402  page 223 : 1 = PVCCIO_CPU1 ; 2 = SVID_CLK1_CPU1_R
R9U7  RES  0.0 5% CHIP  pkg 0402  page 223 : 1 = FM_PVDDQ_GHJ_EN ; 2 = VR_PVDDQ_GHJ_VREN
R9U8  RES  100.0K 1% EMPTY  pkg 0402  page 223 : 1 = P3V3_STBY ; 2 = VR_PVDDQ_GHJ_VREN
R9U10  RES  0.0 5% CHIP  pkg 0402  page 223 : 1 = P3V3_STBY ; 2 = VR_PVDDQ_GHJ_VDD
R9U12  RES  0.0 5% CHIP  pkg 0402  page 224 : 1 = VR_PVDDQ_GHJ_PH2_VCIN ; 2 = P5V_STBY
R9W1  RES  10.0K 1% CHIP  pkg 0402  page 186 : 1 = P3V3_STBY ; 2 = FM_MEZZA_PRSNT1_N
R9W12  RES  10.0K 1% CHIP  pkg 0402  page 239 : 1 = P3V3_STBY ; 2 = PWRGD_P2V5_BMC_STBY_R
R9W13  RES  20.0 1% CHIP  pkg 0402  page 248 : 1 = SMB_PEHPCPU0_STBY_LVC3_R_SDA ; 2 = SMB_PEHPCPU0_STBY_LVC3_SDA
R9W14  RES  20.0 1% CHIP  pkg 0402  page 248 : 1 = SMB_PEHPCPU0_STBY_LVC3_R_SCL ; 2 = SMB_PEHPCPU0_STBY_LVC3_SCL
R9W16  RES  2.0K 1% CHIP  pkg 0402  page 248 : 1 = P3V3_STBY ; 2 = SMB_PEHPCPU0_STBY_LVC3_R_SDA
R9W17  RES  2.0K 1% CHIP  pkg 0402  page 248 : 1 = P3V3_STBY ; 2 = SMB_PEHPCPU0_STBY_LVC3_R_SCL
R9W18  RES  240 1.0% CHIP  pkg 0402  page 248 : 1 = PVCCIO_CPU0 ; 2 = SMB_CPU0_PE_HP_GTL_R_SDA
R9W19  RES  240 1.0% CHIP  pkg 0402  page 248 : 1 = PVCCIO_CPU0 ; 2 = SMB_CPU0_PE_HP_GTL_R_SCL
R9W31  21K5R2F-GP  1%  pkg RCL_GP  page 239 : 1 = P2V5_AUX_BMC ; 2 = VR_P2V5_BMC_STBY_FB
R9W32  RES  10.0K 1% CHIP  pkg 0402  page 239 : 1 = VR_P2V5_BMC_STBY_FB ; 2 = GND
R9W33  RES  4.75K 1% CHIP  pkg 0402  page 158 : 1 = P3V3_STBY ; 2 = SP1_BMC_HOST_UART_RX
R9W34  RES  4.75K 1% CHIP  pkg 0402  page 158 : 1 = P3V3_STBY ; 2 = UART_BMC_RXD5
R9W35  RES  4.75K 1% CHIP  pkg 0402  page 158 : 1 = P3V3_STBY ; 2 = SP2_BMC_CM_UART_RX_R
R9W36  RES  10.0K 1% CHIP  pkg 0402  page 139 : 1 = P3V3_STBY ; 2 = PU_DEV_OFF_N
R10W1  RES  100.0 1% CHIP  pkg 0402  page 251 : 1 = PUMP_TACH0 ; 2 = PUMP_TACH_R
R10W2  RES  4.75K 1% CHIP  pkg 0402  page 251 : 1 = P3V3_STBY ; 2 = PUMP_TACH0
R10W3  RES  4.75K 1% CHIP  pkg 0402  page 251 : 1 = P5V_STBY ; 2 = PUMP_PWM_OUT_R
R10W4  RES  221 1.0% CHIP  pkg 0402  page 251 : 1 = PUMP_PWM_OUT_BUF ; 2 = PUMP_PWM_OUT_R
R10W5  RES  0.0 5% CHIP  pkg 0805  page 251 : 1 = P12V_FAN ; 2 = P12V_PUMP
R10W6  RES  100.0 1% CHIP  pkg 0402  page 251 : 1 = PUMP_TACH1 ; 2 = PUMP_TACH1_R
R10W7  RES  4.75K 1% CHIP  pkg 0402  page 251 : 1 = P3V3_STBY ; 2 = PUMP_TACH1
R12W1  665KR5B-1-GP  0.1%  pkg SMD-RG3  page 197 : 1 = P12V_STBY ; 2 = VR_PVDDQ_ABC_AIINSEN
R12W2  665KR5B-1-GP  0.1%  pkg SMD-RG3  page 197 : 1 = P12V_NVDIMM_ABC_D ; 2 = VR_PVDDQ_ABC_VINSEN
R12W3  4D02R2F-GP  1%  pkg SMD-RG2  page 197 : 1 = P12V_STBY ; 2 = P12V_NVDIMM_ABC_D
R12W4  RES  100.0K 1% CHIP  pkg 0603  page 197 : 1 = P12V_NVDIMM_ABC ; 2 = PWRGD_PVDDQ_ABC_N
R12W5  665KR2B-GP  0.1%  pkg SMD-RG2  page 197 : 1 = VR_PVDDQ_ABC_AIINSEN ; 2 = VR_PVDDQ_ABC_VINSEN
R12W6  665KR5B-1-GP  0.1%  pkg SMD-RG3  page 197 : 1 = P12V_STBY ; 2 = VR_PVDDQ_DEF_AIINSEN
R12W7  665KR5B-1-GP  0.1%  pkg SMD-RG3  page 197 : 1 = P12V_NVDIMM_DEF_D ; 2 = VR_PVDDQ_DEF_VINSEN
R12W8  4D02R2F-GP  1%  pkg SMD-RG2  page 197 : 1 = P12V_STBY ; 2 = P12V_NVDIMM_DEF_D
R12W9  RES  100.0K 1% CHIP  pkg 0603  page 197 : 1 = P12V_NVDIMM_DEF ; 2 = PWRGD_PVDDQ_DEF_N
R12W10  665KR2B-GP  0.1%  pkg SMD-RG2  page 197 : 1 = VR_PVDDQ_DEF_AIINSEN ; 2 = VR_PVDDQ_DEF_VINSEN
R12W11  665KR5B-1-GP  0.1%  pkg SMD-RG3  page 197 : 1 = P12V_STBY ; 2 = VR_PVDDQ_GHJ_AIINSEN
R12W12  665KR5B-1-GP  0.1%  pkg SMD-RG3  page 197 : 1 = P12V_NVDIMM_GHJ_D ; 2 = VR_PVDDQ_GHJ_VINSEN
R12W13  4D02R2F-GP  1%  pkg SMD-RG2  page 197 : 1 = P12V_STBY ; 2 = P12V_NVDIMM_GHJ_D
R12W14  RES  100.0K 1% CHIP  pkg 0603  page 197 : 1 = P12V_NVDIMM_GHJ ; 2 = PWRGD_PVDDQ_GHJ_N
R12W15  665KR2B-GP  0.1%  pkg SMD-RG2  page 197 : 1 = VR_PVDDQ_GHJ_AIINSEN ; 2 = VR_PVDDQ_GHJ_VINSEN
R12W16  665KR5B-1-GP  0.1%  pkg SMD-RG3  page 197 : 1 = P12V_STBY ; 2 = VR_PVDDQ_KLM_AIINSEN
R12W17  665KR5B-1-GP  0.1%  pkg SMD-RG3  page 197 : 1 = P12V_NVDIMM_KLM_D ; 2 = VR_PVDDQ_KLM_VINSEN
R12W18  4D02R2F-GP  1%  pkg SMD-RG2  page 197 : 1 = P12V_STBY ; 2 = P12V_NVDIMM_KLM_D
R12W19  RES  100.0K 1% CHIP  pkg 0603  page 197 : 1 = P12V_NVDIMM_KLM ; 2 = PWRGD_PVDDQ_KLM_N
R12W20  665KR2B-GP  0.1%  pkg SMD-RG2  page 197 : 1 = VR_PVDDQ_KLM_AIINSEN ; 2 = VR_PVDDQ_KLM_VINSEN
R12W25  RES  0.0 5% CHIP  pkg 0402  page 215 : 1 = PU_VR_PVDDQ_ABC_FAULT1 ; 2 = PWRGD_PVDDQ_ABC
R12W26  RES  0.0 5% EMPTY  pkg 0402  page 215 : 1 = TP_PVDDQ_ABC_MP1 ; 2 = PWRGD_PVDDQ_ABC
R12W27  RES  0.0 5% EMPTY  pkg 0402  page 215 : 1 = TP_PVDDQ_ABC_MP2 ; 2 = PWRGD_PVDDQ_ABC
R12W28  RES  0.0 5% CHIP  pkg 0402  page 218 : 1 = PU_VR_PVDDQ_DEF_FAULT1 ; 2 = PWRGD_PVDDQ_DEF
R12W29  RES  0.0 5% EMPTY  pkg 0402  page 218 : 1 = TP_PVDDQ_DEF_MP1 ; 2 = PWRGD_PVDDQ_DEF
